# T6G (Grand Teton) — schematic netlist excerpt (pin names and nets, part order shuffled) for the footprints in the layout excerpt that follows; sources: Cadence DE-HDL packaged netlist, KiCad conversion of 04192023_DAF0TMB3IC0_F0TG_MB_C_brd_V02_OCP.brd

C2415  Q_CAP  22UF 4V 20% X6S  pkg C0402  page 74 : A = PVDDCR_SOC_P1 ; B = GND
PR108  Q_RES  2.2 1% CHIP  pkg 0402LF  page 206 : A = PVDDCR_CPU1_P0_PVCC ; B = PVDDIO_P0_VCC3

(kicad_pcb
	(version 20260206)
	(generator "pcbnew")
	(generator_version "10.0")
	(general
		(thickness 1.6)
		(legacy_teardrops no)
	)
	(paper "A4")
	(title_block
		(title "04192023_DAF0TMB3IC0_F0TG_MB_C_brd_V02_OCP.brd")
		(comment 1 "Grand Teton / footprints 5210-5211 of 8354")
	)
	(layers
		(0 "F.Cu" signal "TOP")
		(4 "In1.Cu" signal "GND")
		(6 "In2.Cu" signal "IN1")
		(8 "In3.Cu" signal "GND1")
		(10 "In4.Cu" signal "IN2")
		(12 "In5.Cu" signal "GND2")
		(14 "In6.Cu" signal "IN3")
		(16 "In7.Cu" signal "GND3")
		(18 "In8.Cu" signal "VCC")
		(20 "In9.Cu" signal "VCC1")
		(22 "In10.Cu" signal "GND4")
		(24 "In11.Cu" signal "IN4")
		(26 "In12.Cu" signal "GND5")
		(28 "In13.Cu" signal "IN5")
		(30 "In14.Cu" signal "GND6")
		(32 "In15.Cu" signal "IN6")
		(34 "In16.Cu" signal "GND7")
		(2 "B.Cu" signal "BOTTOM")
		(9 "F.Adhes" user "F.Adhesive")
		(11 "B.Adhes" user "B.Adhesive")
		(13 "F.Paste" user "Package Geometry/Pastemask Top")
		(15 "B.Paste" user "Package Geometry/Pastemask Bottom")
		(5 "F.SilkS" user "Ref Des/Silkscreen Top")
		(7 "B.SilkS" user "Ref Des/Silkscreen Bottom")
		(1 "F.Mask" user "Board Geometry/Soldermask Top")
		(3 "B.Mask" user "Board Geometry/Soldermask Bottom")
		(17 "Dwgs.User" user "User.Drawings")
		(19 "Cmts.User" user "User.Comments")
		(21 "Eco1.User" user "User.Eco1")
		(23 "Eco2.User" user "User.Eco2")
		(25 "Edge.Cuts" user "Board Geometry/Outline")
		(27 "Margin" user)
		(31 "F.CrtYd" user "Package Geometry/Place Bound Top")
		(29 "B.CrtYd" user "Package Geometry/Place Bound Bottom")
		(35 "F.Fab" user "Ref Des/Assembly Top")
		(33 "B.Fab" user "Ref Des/Assembly Bottom")
	)
	(footprint ""
		(layer "B.Cu")
		(at 281.391614 -347.77553 -90)
		(property "Reference" "PR108"
			(at 0 0 90)
			(layer "B.SilkS")
			(hide yes)
			(effects
				(font
					(size 1.27 1.27)
				)
				(justify mirror)
			)
		)
		(property "Value" ""
			(at 0 0 90)
			(layer "B.Fab")
			(effects
				(font
					(size 1.27 1.27)
				)
				(justify mirror)
			)
		)
		(duplicate_pad_numbers_are_jumpers no)
		(fp_line
			(start -0.7874 0.4064)
			(end 0.7874 0.4064)
			(stroke
				(width 0.1524)
				(type default)
			)
			(layer "B.SilkS")
		)
		(fp_line
			(start 0.7874 0.4064)
			(end 0.7874 -0.4064)
			(stroke
				(width 0.1524)
				(type default)
			)
			(layer "B.SilkS")
		)
		(fp_line
			(start -0.7874 -0.4064)
			(end -0.7874 0.4064)
			(stroke
				(width 0.1524)
				(type default)
			)
			(layer "B.SilkS")
		)
		(fp_line
			(start 0.7874 -0.4064)
			(end -0.7874 -0.4064)
			(stroke
				(width 0.1524)
				(type default)
			)
			(layer "B.SilkS")
		)
		(fp_line
			(start -0.67945 0.3048)
			(end -0.120396 0.3048)
			(stroke
				(width 0.1)
				(type default)
			)
			(layer "B.Fab")
		)
		(fp_line
			(start -0.120396 0.3048)
			(end -0.120396 0.2794)
			(stroke
				(width 0.1)
				(type default)
			)
			(layer "B.Fab")
		)
		(fp_line
			(start 0.12065 0.3048)
			(end 0.67945 0.3048)
			(stroke
				(width 0.1)
				(type default)
			)
			(layer "B.Fab")
		)
		(fp_line
			(start 0.67945 0.3048)
			(end 0.67945 -0.305054)
			(stroke
				(width 0.1)
				(type default)
			)
			(layer "B.Fab")
		)
		(fp_line
			(start -0.120396 0.2794)
			(end 0.12065 0.2794)
			(stroke
				(width 0.1)
				(type default)
			)
			(layer "B.Fab")
		)
		(fp_line
			(start 0.12065 0.2794)
			(end 0.12065 0.3048)
			(stroke
				(width 0.1)
				(type default)
			)
			(layer "B.Fab")
		)
		(fp_line
			(start -0.12065 -0.2794)
			(end -0.12065 -0.3048)
			(stroke
				(width 0.1)
				(type default)
			)
			(layer "B.Fab")
		)
		(fp_line
			(start 0.12065 -0.2794)
			(end -0.12065 -0.2794)
			(stroke
				(width 0.1)
				(type default)
			)
			(layer "B.Fab")
		)
		(fp_line
			(start -0.67945 -0.3048)
			(end -0.67945 0.3048)
			(stroke
				(width 0.1)
				(type default)
			)
			(layer "B.Fab")
		)
		(fp_line
			(start -0.12065 -0.3048)
			(end -0.67945 -0.3048)
			(stroke
				(width 0.1)
				(type default)
			)
			(layer "B.Fab")
		)
		(fp_line
			(start 0.12065 -0.305054)
			(end 0.12065 -0.2794)
			(stroke
				(width 0.1)
				(type default)
			)
			(layer "B.Fab")
		)
		(fp_line
			(start 0.67945 -0.305054)
			(end 0.12065 -0.305054)
			(stroke
				(width 0.1)
				(type default)
			)
			(layer "B.Fab")
		)
		(pad "1" smd circle
			(at 0.40005 0 90)
			(size 0 0)
			(layers "B.Cu" "B.Mask" "B.Paste")
			(net "PVDDCR_CPU1_P0_PVCC")
		)
		(pad "2" smd circle
			(at -0.40005 0 90)
			(size 0 0)
			(layers "B.Cu" "B.Mask" "B.Paste")
			(net "PVDDIO_P0_VCC3")
		)
	)
	(footprint ""
		(layer "B.Cu")
		(at 117.388386 -253.432564)
		(property "Reference" "C2415"
			(at 0 0 0)
			(layer "B.SilkS")
			(hide yes)
			(effects
				(font
					(size 1.27 1.27)
				)
				(justify mirror)
			)
		)
		(property "Value" ""
			(at 0 0 0)
			(layer "B.Fab")
			(effects
				(font
					(size 1.27 1.27)
				)
				(justify mirror)
			)
		)
		(duplicate_pad_numbers_are_jumpers no)
		(fp_line
			(start -0.7874 -0.4064)
			(end -0.7874 0.4064)
			(stroke
				(width 0.1524)
				(type default)
			)
			(layer "B.SilkS")
		)
		(fp_line
			(start -0.7874 0.4064)
			(end 0.7874 0.4064)
			(stroke
				(width 0.1524)
				(type default)
			)
			(layer "B.SilkS")
		)
		(fp_line
			(start 0.7874 -0.4064)
			(end -0.7874 -0.4064)
			(stroke
				(width 0.1524)
				(type default)
			)
			(layer "B.SilkS")
		)
		(fp_line
			(start 0.7874 0.4064)
			(end 0.7874 -0.4064)
			(stroke
				(width 0.1524)
				(type default)
			)
			(layer "B.SilkS")
		)
		(fp_line
			(start -0.67945 -0.3048)
			(end -0.67945 0.3048)
			(stroke
				(width 0.1)
				(type default)
			)
			(layer "B.Fab")
		)
		(fp_line
			(start -0.67945 0.3048)
			(end -0.120396 0.3048)
			(stroke
				(width 0.1)
				(type default)
			)
			(layer "B.Fab")
		)
		(fp_line
			(start -0.12065 -0.3048)
			(end -0.67945 -0.3048)
			(stroke
				(width 0.1)
				(type default)
			)
			(layer "B.Fab")
		)
		(fp_line
			(start -0.12065 -0.2794)
			(end -0.12065 -0.3048)
			(stroke
				(width 0.1)
				(type default)
			)
			(layer "B.Fab")
		)
		(fp_line
			(start -0.120396 0.2794)
			(end 0.12065 0.2794)
			(stroke
				(width 0.1)
				(type default)
			)
			(layer "B.Fab")
		)
		(fp_line
			(start -0.120396 0.3048)
			(end -0.120396 0.2794)
			(stroke
				(width 0.1)
				(type default)
			)
			(layer "B.Fab")
		)
		(fp_line
			(start 0.12065 -0.305054)
			(end 0.12065 -0.2794)
			(stroke
				(width 0.1)
				(type default)
			)
			(layer "B.Fab")
		)
		(fp_line
			(start 0.12065 -0.2794)
			(end -0.12065 -0.2794)
			(stroke
				(width 0.1)
				(type default)
			)
			(layer "B.Fab")
		)
		(fp_line
			(start 0.12065 0.2794)
			(end 0.12065 0.3048)
			(stroke
				(width 0.1)
				(type default)
			)
			(layer "B.Fab")
		)
		(fp_line
			(start 0.12065 0.3048)
			(end 0.67945 0.3048)
			(stroke
				(width 0.1)
				(type default)
			)
			(layer "B.Fab")
		)
		(fp_line
			(start 0.67945 -0.305054)
			(end 0.12065 -0.305054)
			(stroke
				(width 0.1)
				(type default)
			)
			(layer "B.Fab")
		)
		(fp_line
			(start 0.67945 0.3048)
			(end 0.67945 -0.305054)
			(stroke
				(width 0.1)
				(type default)
			)
			(layer "B.Fab")
		)
		(pad "1" smd circle
			(at 0.40005 0 180)
			(size 0 0)
			(layers "B.Cu" "B.Mask" "B.Paste")
			(net "PVDDCR_SOC_P1")
		)
		(pad "2" smd circle
			(at -0.40005 0 180)
			(size 0 0)
			(layers "B.Cu" "B.Mask" "B.Paste")
			(net "GND")
		)
	)
)
